(kicad_pcb
	(version 20260206)
	(generator "pcbnew")
	(generator_version "10.0")
	(general
		(thickness 1.6)
		(legacy_teardrops no)
	)
	(paper "A4")
	(title_block
		(title "9052_F0T_PDB_Converter_Brick_F_V03_1208_1600_OCP.brd")
		(comment 1 "Grand Teton / footprints 93-99 of 578")
	)
	(layers
		(0 "F.Cu" signal "TOP")
		(4 "In1.Cu" signal "GND")
		(6 "In2.Cu" signal "IN1")
		(8 "In3.Cu" signal "GND1")
		(10 "In4.Cu" signal "VCC")
		(12 "In5.Cu" signal "VCC1")
		(14 "In6.Cu" signal "GND2")
		(16 "In7.Cu" signal "IN2")
		(18 "In8.Cu" signal "GND3")
		(2 "B.Cu" signal "BOTTOM")
		(9 "F.Adhes" user "F.Adhesive")
		(11 "B.Adhes" user "B.Adhesive")
		(13 "F.Paste" user "Package Geometry/Pastemask Top")
		(15 "B.Paste" user "Package Geometry/Pastemask Bottom")
		(5 "F.SilkS" user "Ref Des/Silkscreen Top")
		(7 "B.SilkS" user "Ref Des/Silkscreen Bottom")
		(1 "F.Mask" user "Board Geometry/Soldermask Top")
		(3 "B.Mask" user "Board Geometry/Soldermask Bottom")
		(17 "Dwgs.User" user "User.Drawings")
		(19 "Cmts.User" user "User.Comments")
		(21 "Eco1.User" user "User.Eco1")
		(23 "Eco2.User" user "User.Eco2")
		(25 "Edge.Cuts" user "Board Geometry/Outline")
		(27 "Margin" user)
		(31 "F.CrtYd" user "Package Geometry/Place Bound Top")
		(29 "B.CrtYd" user "Package Geometry/Place Bound Bottom")
		(35 "F.Fab" user "Ref Des/Assembly Top")
		(33 "B.Fab" user "Ref Des/Assembly Bottom")
	)
	(footprint ""
		(layer "F.Cu")
		(at 260.35 -34.798 -90)
		(property "Reference" "PC3"
			(at 0 0 270)
			(layer "F.SilkS")
			(hide yes)
			(effects
				(font
					(size 1.27 1.27)
				)
			)
		)
		(property "Value" ""
			(at 0 0 270)
			(layer "F.Fab")
			(effects
				(font
					(size 1.27 1.27)
				)
			)
		)
		(duplicate_pad_numbers_are_jumpers no)
		(fp_line
			(start -2.2098 0.9398)
			(end -2.2098 -0.9398)
			(stroke
				(width 0.1524)
				(type default)
			)
			(layer "F.SilkS")
		)
		(fp_line
			(start 2.2098 0.9398)
			(end -2.2098 0.9398)
			(stroke
				(width 0.1524)
				(type default)
			)
			(layer "F.SilkS")
		)
		(fp_line
			(start -2.2098 -0.9398)
			(end 2.2098 -0.9398)
			(stroke
				(width 0.1524)
				(type default)
			)
			(layer "F.SilkS")
		)
		(fp_line
			(start 2.2098 -0.9398)
			(end 2.2098 0.9398)
			(stroke
				(width 0.1524)
				(type default)
			)
			(layer "F.SilkS")
		)
		(fp_line
			(start -1.6764 0.9398)
			(end -1.6764 0.889)
			(stroke
				(width 0.1)
				(type default)
			)
			(layer "F.Fab")
		)
		(fp_line
			(start 1.6764 0.9398)
			(end -1.6764 0.9398)
			(stroke
				(width 0.1)
				(type default)
			)
			(layer "F.Fab")
		)
		(fp_line
			(start -1.6764 0.889)
			(end -1.6764 0.8382)
			(stroke
				(width 0.1)
				(type default)
			)
			(layer "F.Fab")
		)
		(fp_line
			(start 1.6764 0.889)
			(end 1.6764 0.9398)
			(stroke
				(width 0.1)
				(type default)
			)
			(layer "F.Fab")
		)
		(fp_line
			(start -2.1082 0.8382)
			(end -2.1082 -0.8382)
			(stroke
				(width 0.1)
				(type default)
			)
			(layer "F.Fab")
		)
		(fp_line
			(start -1.6764 0.8382)
			(end -2.1082 0.8382)
			(stroke
				(width 0.1)
				(type default)
			)
			(layer "F.Fab")
		)
		(fp_line
			(start 1.6764 0.8382)
			(end 1.6764 0.889)
			(stroke
				(width 0.1)
				(type default)
			)
			(layer "F.Fab")
		)
		(fp_line
			(start 2.1082 0.8382)
			(end 1.6764 0.8382)
			(stroke
				(width 0.1)
				(type default)
			)
			(layer "F.Fab")
		)
		(fp_line
			(start -2.1082 -0.8382)
			(end -1.6764 -0.8382)
			(stroke
				(width 0.1)
				(type default)
			)
			(layer "F.Fab")
		)
		(fp_line
			(start -1.6764 -0.8382)
			(end -1.6764 -0.889)
			(stroke
				(width 0.1)
				(type default)
			)
			(layer "F.Fab")
		)
		(fp_line
			(start 1.6764 -0.8382)
			(end 2.1082 -0.8382)
			(stroke
				(width 0.1)
				(type default)
			)
			(layer "F.Fab")
		)
		(fp_line
			(start 2.1082 -0.8382)
			(end 2.1082 0.8382)
			(stroke
				(width 0.1)
				(type default)
			)
			(layer "F.Fab")
		)
		(fp_line
			(start -1.6764 -0.889)
			(end -1.6764 -0.9398)
			(stroke
				(width 0.1)
				(type default)
			)
			(layer "F.Fab")
		)
		(fp_line
			(start 1.6764 -0.889)
			(end 1.6764 -0.8382)
			(stroke
				(width 0.1)
				(type default)
			)
			(layer "F.Fab")
		)
		(fp_line
			(start -1.6764 -0.9398)
			(end 1.6764 -0.9398)
			(stroke
				(width 0.1)
				(type default)
			)
			(layer "F.Fab")
		)
		(fp_line
			(start 1.6764 -0.9398)
			(end 1.6764 -0.889)
			(stroke
				(width 0.1)
				(type default)
			)
			(layer "F.Fab")
		)
		(pad "1" smd rect
			(at -1.4732 0 90)
			(size 1.1684 1.5748)
			(layers "F.Cu" "F.Mask" "F.Paste")
			(net "P52V_1_R")
		)
		(pad "2" smd rect
			(at 1.4732 0 90)
			(size 1.1684 1.5748)
			(layers "F.Cu" "F.Mask" "F.Paste")
			(net "GND_FIELD_SIGNAL")
		)
	)
	(footprint ""
		(layer "F.Cu")
		(at 90.043 -51.943)
		(property "Reference" "PC88"
			(at 0 0 0)
			(layer "F.SilkS")
			(hide yes)
			(effects
				(font
					(size 1.27 1.27)
				)
			)
		)
		(property "Value" ""
			(at 0 0 0)
			(layer "F.Fab")
			(effects
				(font
					(size 1.27 1.27)
				)
			)
		)
		(duplicate_pad_numbers_are_jumpers no)
		(fp_line
			(start -1.524 -0.762)
			(end 1.524 -0.762)
			(stroke
				(width 0.1524)
				(type default)
			)
			(layer "F.SilkS")
		)
		(fp_line
			(start -1.524 0.762)
			(end -1.524 -0.762)
			(stroke
				(width 0.1524)
				(type default)
			)
			(layer "F.SilkS")
		)
		(fp_line
			(start 1.524 -0.762)
			(end 1.524 0.762)
			(stroke
				(width 0.1524)
				(type default)
			)
			(layer "F.SilkS")
		)
		(fp_line
			(start 1.524 0.762)
			(end -1.524 0.762)
			(stroke
				(width 0.1524)
				(type default)
			)
			(layer "F.SilkS")
		)
		(fp_line
			(start -1.1049 -0.724916)
			(end -1.1049 0.724916)
			(stroke
				(width 0.1)
				(type default)
			)
			(layer "F.Fab")
		)
		(fp_line
			(start -1.1049 0.724916)
			(end 1.1049 0.724916)
			(stroke
				(width 0.1)
				(type default)
			)
			(layer "F.Fab")
		)
		(fp_line
			(start 1.1049 -0.724916)
			(end -1.1049 -0.724916)
			(stroke
				(width 0.1)
				(type default)
			)
			(layer "F.Fab")
		)
		(fp_line
			(start 1.1049 0.724916)
			(end 1.1049 -0.724916)
			(stroke
				(width 0.1)
				(type default)
			)
			(layer "F.Fab")
		)
		(pad "1" smd rect
			(at -0.889 0 180)
			(size 1.016 1.27)
			(layers "F.Cu" "F.Mask" "F.Paste")
			(net "P12V_BRICK")
		)
		(pad "2" smd rect
			(at 0.889 0 180)
			(size 1.016 1.27)
			(layers "F.Cu" "F.Mask" "F.Paste")
			(net "GND")
		)
	)
	(footprint ""
		(layer "F.Cu")
		(at 282.956 -49.276 90)
		(property "Reference" "PC1"
			(at 0 0 90)
			(layer "F.SilkS")
			(hide yes)
			(effects
				(font
					(size 1.27 1.27)
				)
			)
		)
		(property "Value" ""
			(at 0 0 90)
			(layer "F.Fab")
			(effects
				(font
					(size 1.27 1.27)
				)
			)
		)
		(duplicate_pad_numbers_are_jumpers no)
		(fp_line
			(start 0.7874 -0.4064)
			(end 0.7874 0.4064)
			(stroke
				(width 0.1524)
				(type default)
			)
			(layer "F.SilkS")
		)
		(fp_line
			(start -0.7874 -0.4064)
			(end 0.7874 -0.4064)
			(stroke
				(width 0.1524)
				(type default)
			)
			(layer "F.SilkS")
		)
		(fp_line
			(start 0.7874 0.4064)
			(end -0.7874 0.4064)
			(stroke
				(width 0.1524)
				(type default)
			)
			(layer "F.SilkS")
		)
		(fp_line
			(start -0.7874 0.4064)
			(end -0.7874 -0.4064)
			(stroke
				(width 0.1524)
				(type default)
			)
			(layer "F.SilkS")
		)
		(fp_line
			(start -0.12065 -0.305054)
			(end -0.12065 -0.2794)
			(stroke
				(width 0.1)
				(type default)
			)
			(layer "F.Fab")
		)
		(fp_line
			(start -0.67945 -0.305054)
			(end -0.12065 -0.305054)
			(stroke
				(width 0.1)
				(type default)
			)
			(layer "F.Fab")
		)
		(fp_line
			(start 0.67945 -0.3048)
			(end 0.67945 0.3048)
			(stroke
				(width 0.1)
				(type default)
			)
			(layer "F.Fab")
		)
		(fp_line
			(start 0.12065 -0.3048)
			(end 0.67945 -0.3048)
			(stroke
				(width 0.1)
				(type default)
			)
			(layer "F.Fab")
		)
		(fp_line
			(start 0.12065 -0.2794)
			(end 0.12065 -0.3048)
			(stroke
				(width 0.1)
				(type default)
			)
			(layer "F.Fab")
		)
		(fp_line
			(start -0.12065 -0.2794)
			(end 0.12065 -0.2794)
			(stroke
				(width 0.1)
				(type default)
			)
			(layer "F.Fab")
		)
		(fp_line
			(start 0.120396 0.2794)
			(end -0.12065 0.2794)
			(stroke
				(width 0.1)
				(type default)
			)
			(layer "F.Fab")
		)
		(fp_line
			(start -0.12065 0.2794)
			(end -0.12065 0.3048)
			(stroke
				(width 0.1)
				(type default)
			)
			(layer "F.Fab")
		)
		(fp_line
			(start 0.67945 0.3048)
			(end 0.120396 0.3048)
			(stroke
				(width 0.1)
				(type default)
			)
			(layer "F.Fab")
		)
		(fp_line
			(start 0.120396 0.3048)
			(end 0.120396 0.2794)
			(stroke
				(width 0.1)
				(type default)
			)
			(layer "F.Fab")
		)
		(fp_line
			(start -0.12065 0.3048)
			(end -0.67945 0.3048)
			(stroke
				(width 0.1)
				(type default)
			)
			(layer "F.Fab")
		)
		(fp_line
			(start -0.67945 0.3048)
			(end -0.67945 -0.305054)
			(stroke
				(width 0.1)
				(type default)
			)
			(layer "F.Fab")
		)
		(pad "1" smd circle
			(at -0.40005 0 90)
			(size 0 0)
			(layers "F.Cu" "F.Mask" "F.Paste")
			(net "P52V_HS1_OV")
		)
		(pad "2" smd circle
			(at 0.40005 0 90)
			(size 0 0)
			(layers "F.Cu" "F.Mask" "F.Paste")
			(net "GND_FIELD_SIGNAL")
		)
	)
	(footprint ""
		(layer "F.Cu")
		(at 279.010872 -40.744902)
		(property "Reference" "R81"
			(at 0 0 0)
			(layer "F.SilkS")
			(hide yes)
			(effects
				(font
					(size 1.27 1.27)
				)
			)
		)
		(property "Value" ""
			(at 0 0 0)
			(layer "F.Fab")
			(effects
				(font
					(size 1.27 1.27)
				)
			)
		)
		(duplicate_pad_numbers_are_jumpers no)
		(fp_line
			(start -0.7874 -0.4064)
			(end 0.7874 -0.4064)
			(stroke
				(width 0.1524)
				(type default)
			)
			(layer "F.SilkS")
		)
		(fp_line
			(start -0.7874 0.4064)
			(end -0.7874 -0.4064)
			(stroke
				(width 0.1524)
				(type default)
			)
			(layer "F.SilkS")
		)
		(fp_line
			(start 0.7874 -0.4064)
			(end 0.7874 0.4064)
			(stroke
				(width 0.1524)
				(type default)
			)
			(layer "F.SilkS")
		)
		(fp_line
			(start 0.7874 0.4064)
			(end -0.7874 0.4064)
			(stroke
				(width 0.1524)
				(type default)
			)
			(layer "F.SilkS")
		)
		(fp_line
			(start -0.67945 -0.305054)
			(end -0.12065 -0.305054)
			(stroke
				(width 0.1)
				(type default)
			)
			(layer "F.Fab")
		)
		(fp_line
			(start -0.67945 0.3048)
			(end -0.67945 -0.305054)
			(stroke
				(width 0.1)
				(type default)
			)
			(layer "F.Fab")
		)
		(fp_line
			(start -0.12065 -0.305054)
			(end -0.12065 -0.2794)
			(stroke
				(width 0.1)
				(type default)
			)
			(layer "F.Fab")
		)
		(fp_line
			(start -0.12065 -0.2794)
			(end 0.12065 -0.2794)
			(stroke
				(width 0.1)
				(type default)
			)
			(layer "F.Fab")
		)
		(fp_line
			(start -0.12065 0.2794)
			(end -0.12065 0.3048)
			(stroke
				(width 0.1)
				(type default)
			)
			(layer "F.Fab")
		)
		(fp_line
			(start -0.12065 0.3048)
			(end -0.67945 0.3048)
			(stroke
				(width 0.1)
				(type default)
			)
			(layer "F.Fab")
		)
		(fp_line
			(start 0.120396 0.2794)
			(end -0.12065 0.2794)
			(stroke
				(width 0.1)
				(type default)
			)
			(layer "F.Fab")
		)
		(fp_line
			(start 0.120396 0.3048)
			(end 0.120396 0.2794)
			(stroke
				(width 0.1)
				(type default)
			)
			(layer "F.Fab")
		)
		(fp_line
			(start 0.12065 -0.3048)
			(end 0.67945 -0.3048)
			(stroke
				(width 0.1)
				(type default)
			)
			(layer "F.Fab")
		)
		(fp_line
			(start 0.12065 -0.2794)
			(end 0.12065 -0.3048)
			(stroke
				(width 0.1)
				(type default)
			)
			(layer "F.Fab")
		)
		(fp_line
			(start 0.67945 -0.3048)
			(end 0.67945 0.3048)
			(stroke
				(width 0.1)
				(type default)
			)
			(layer "F.Fab")
		)
		(fp_line
			(start 0.67945 0.3048)
			(end 0.120396 0.3048)
			(stroke
				(width 0.1)
				(type default)
			)
			(layer "F.Fab")
		)
		(pad "1" smd circle
			(at -0.40005 0)
			(size 0 0)
			(layers "F.Cu" "F.Mask" "F.Paste")
			(net "SMB_P52V_HSC_SCL")
		)
		(pad "2" smd circle
			(at 0.40005 0)
			(size 0 0)
			(layers "F.Cu" "F.Mask" "F.Paste")
			(net "SMB_P52V_VPDB_SCL_R2")
		)
	)
	(footprint ""
		(layer "F.Cu")
		(at 298.069 -26.797)
		(property "Reference" "C69"
			(at 0 0 0)
			(layer "F.SilkS")
			(hide yes)
			(effects
				(font
					(size 1.27 1.27)
				)
			)
		)
		(property "Value" ""
			(at 0 0 0)
			(layer "F.Fab")
			(effects
				(font
					(size 1.27 1.27)
				)
			)
		)
		(duplicate_pad_numbers_are_jumpers no)
		(fp_line
			(start -1.2954 -0.5842)
			(end 1.2954 -0.5842)
			(stroke
				(width 0.1524)
				(type default)
			)
			(layer "F.SilkS")
		)
		(fp_line
			(start -1.2954 0.5842)
			(end -1.2954 -0.5842)
			(stroke
				(width 0.1524)
				(type default)
			)
			(layer "F.SilkS")
		)
		(fp_line
			(start 1.2954 -0.5842)
			(end 1.2954 0.5842)
			(stroke
				(width 0.1524)
				(type default)
			)
			(layer "F.SilkS")
		)
		(fp_line
			(start 1.2954 0.5842)
			(end -1.2954 0.5842)
			(stroke
				(width 0.1524)
				(type default)
			)
			(layer "F.SilkS")
		)
		(fp_line
			(start -1.1938 -0.4064)
			(end -0.8636 -0.4064)
			(stroke
				(width 0.1)
				(type default)
			)
			(layer "F.Fab")
		)
		(fp_line
			(start -1.1938 0.4064)
			(end -1.1938 -0.4064)
			(stroke
				(width 0.1)
				(type default)
			)
			(layer "F.Fab")
		)
		(fp_line
			(start -0.8636 -0.4572)
			(end 0.8636 -0.4572)
			(stroke
				(width 0.1)
				(type default)
			)
			(layer "F.Fab")
		)
		(fp_line
			(start -0.8636 -0.4064)
			(end -0.8636 -0.4572)
			(stroke
				(width 0.1)
				(type default)
			)
			(layer "F.Fab")
		)
		(fp_line
			(start -0.8636 0.4064)
			(end -1.1938 0.4064)
			(stroke
				(width 0.1)
				(type default)
			)
			(layer "F.Fab")
		)
		(fp_line
			(start -0.8636 0.4572)
			(end -0.8636 0.4064)
			(stroke
				(width 0.1)
				(type default)
			)
			(layer "F.Fab")
		)
		(fp_line
			(start 0.8636 -0.4572)
			(end 0.8636 -0.4064)
			(stroke
				(width 0.1)
				(type default)
			)
			(layer "F.Fab")
		)
		(fp_line
			(start 0.8636 -0.4064)
			(end 1.1938 -0.4064)
			(stroke
				(width 0.1)
				(type default)
			)
			(layer "F.Fab")
		)
		(fp_line
			(start 0.8636 0.4064)
			(end 0.8636 0.4572)
			(stroke
				(width 0.1)
				(type default)
			)
			(layer "F.Fab")
		)
		(fp_line
			(start 0.8636 0.4572)
			(end -0.8636 0.4572)
			(stroke
				(width 0.1)
				(type default)
			)
			(layer "F.Fab")
		)
		(fp_line
			(start 1.1938 -0.4064)
			(end 1.1938 0.4064)
			(stroke
				(width 0.1)
				(type default)
			)
			(layer "F.Fab")
		)
		(fp_line
			(start 1.1938 0.4064)
			(end 0.8636 0.4064)
			(stroke
				(width 0.1)
				(type default)
			)
			(layer "F.Fab")
		)
		(pad "1" smd rect
			(at -0.7366 0 270)
			(size 0.7112 0.8128)
			(layers "F.Cu" "F.Mask" "F.Paste")
			(net "FM_HSC_EN_FUSE")
		)
		(pad "2" smd rect
			(at 0.7366 0 270)
			(size 0.7112 0.8128)
			(layers "F.Cu" "F.Mask" "F.Paste")
			(net "GND")
		)
	)
	(footprint ""
		(layer "F.Cu")
		(at 36.02736 -59.26582 90)
		(property "Reference" "R5893"
			(at 0 0 90)
			(layer "F.SilkS")
			(hide yes)
			(effects
				(font
					(size 1.27 1.27)
				)
			)
		)
		(property "Value" ""
			(at 0 0 90)
			(layer "F.Fab")
			(effects
				(font
					(size 1.27 1.27)
				)
			)
		)
		(duplicate_pad_numbers_are_jumpers no)
		(fp_line
			(start 0.7874 -0.4064)
			(end 0.7874 0.4064)
			(stroke
				(width 0.1524)
				(type default)
			)
			(layer "F.SilkS")
		)
		(fp_line
			(start -0.7874 -0.4064)
			(end 0.7874 -0.4064)
			(stroke
				(width 0.1524)
				(type default)
			)
			(layer "F.SilkS")
		)
		(fp_line
			(start 0.7874 0.4064)
			(end -0.7874 0.4064)
			(stroke
				(width 0.1524)
				(type default)
			)
			(layer "F.SilkS")
		)
		(fp_line
			(start -0.7874 0.4064)
			(end -0.7874 -0.4064)
			(stroke
				(width 0.1524)
				(type default)
			)
			(layer "F.SilkS")
		)
		(fp_line
			(start -0.12065 -0.305054)
			(end -0.12065 -0.2794)
			(stroke
				(width 0.1)
				(type default)
			)
			(layer "F.Fab")
		)
		(fp_line
			(start -0.67945 -0.305054)
			(end -0.12065 -0.305054)
			(stroke
				(width 0.1)
				(type default)
			)
			(layer "F.Fab")
		)
		(fp_line
			(start 0.67945 -0.3048)
			(end 0.67945 0.3048)
			(stroke
				(width 0.1)
				(type default)
			)
			(layer "F.Fab")
		)
		(fp_line
			(start 0.12065 -0.3048)
			(end 0.67945 -0.3048)
			(stroke
				(width 0.1)
				(type default)
			)
			(layer "F.Fab")
		)
		(fp_line
			(start 0.12065 -0.2794)
			(end 0.12065 -0.3048)
			(stroke
				(width 0.1)
				(type default)
			)
			(layer "F.Fab")
		)
		(fp_line
			(start -0.12065 -0.2794)
			(end 0.12065 -0.2794)
			(stroke
				(width 0.1)
				(type default)
			)
			(layer "F.Fab")
		)
		(fp_line
			(start 0.120396 0.2794)
			(end -0.12065 0.2794)
			(stroke
				(width 0.1)
				(type default)
			)
			(layer "F.Fab")
		)
		(fp_line
			(start -0.12065 0.2794)
			(end -0.12065 0.3048)
			(stroke
				(width 0.1)
				(type default)
			)
			(layer "F.Fab")
		)
		(fp_line
			(start 0.67945 0.3048)
			(end 0.120396 0.3048)
			(stroke
				(width 0.1)
				(type default)
			)
			(layer "F.Fab")
		)
		(fp_line
			(start 0.120396 0.3048)
			(end 0.120396 0.2794)
			(stroke
				(width 0.1)
				(type default)
			)
			(layer "F.Fab")
		)
		(fp_line
			(start -0.12065 0.3048)
			(end -0.67945 0.3048)
			(stroke
				(width 0.1)
				(type default)
			)
			(layer "F.Fab")
		)
		(fp_line
			(start -0.67945 0.3048)
			(end -0.67945 -0.305054)
			(stroke
				(width 0.1)
				(type default)
			)
			(layer "F.Fab")
		)
		(pad "1" smd rect
			(at -0.40005 0 270)
			(size 0.4572 0.508)
			(layers "F.Cu" "F.Mask" "F.Paste")
			(net "P12V_HPDB")
		)
		(pad "2" smd rect
			(at 0.40005 0 270)
			(size 0.4572 0.508)
			(layers "F.Cu" "F.Mask" "F.Paste")
			(net "P12V_HPDB_0_PD")
		)
	)
	(footprint ""
		(layer "F.Cu")
		(at 84.582 -49.911)
		(property "Reference" "PC91"
			(at 0 0 0)
			(layer "F.SilkS")
			(hide yes)
			(effects
				(font
					(size 1.27 1.27)
				)
			)
		)
		(property "Value" ""
			(at 0 0 0)
			(layer "F.Fab")
			(effects
				(font
					(size 1.27 1.27)
				)
			)
		)
		(duplicate_pad_numbers_are_jumpers no)
		(fp_line
			(start -1.524 -0.762)
			(end 1.524 -0.762)
			(stroke
				(width 0.1524)
				(type default)
			)
			(layer "F.SilkS")
		)
		(fp_line
			(start -1.524 0.762)
			(end -1.524 -0.762)
			(stroke
				(width 0.1524)
				(type default)
			)
			(layer "F.SilkS")
		)
		(fp_line
			(start 1.524 -0.762)
			(end 1.524 0.762)
			(stroke
				(width 0.1524)
				(type default)
			)
			(layer "F.SilkS")
		)
		(fp_line
			(start 1.524 0.762)
			(end -1.524 0.762)
			(stroke
				(width 0.1524)
				(type default)
			)
			(layer "F.SilkS")
		)
		(fp_line
			(start -1.1049 -0.724916)
			(end -1.1049 0.724916)
			(stroke
				(width 0.1)
				(type default)
			)
			(layer "F.Fab")
		)
		(fp_line
			(start -1.1049 0.724916)
			(end 1.1049 0.724916)
			(stroke
				(width 0.1)
				(type default)
			)
			(layer "F.Fab")
		)
		(fp_line
			(start 1.1049 -0.724916)
			(end -1.1049 -0.724916)
			(stroke
				(width 0.1)
				(type default)
			)
			(layer "F.Fab")
		)
		(fp_line
			(start 1.1049 0.724916)
			(end 1.1049 -0.724916)
			(stroke
				(width 0.1)
				(type default)
			)
			(layer "F.Fab")
		)
		(pad "1" smd rect
			(at -0.889 0 180)
			(size 1.016 1.27)
			(layers "F.Cu" "F.Mask" "F.Paste")
			(net "P12V_BRICK")
		)
		(pad "2" smd rect
			(at 0.889 0 180)
			(size 1.016 1.27)
			(layers "F.Cu" "F.Mask" "F.Paste")
			(net "GND")
		)
	)
)
